# S9S_MB_2U (Grand Teton) — schematic netlist excerpt (pin names and nets, part order shuffled) for the footprints in the layout excerpt that follows; sources: Cadence DE-HDL packaged netlist, KiCad conversion of 03242023_DA0F0TMBIJ0_F0T_Motherboard_J_brd_V01_OCP.brd

C1874  Q_CAP  0.1UF 25V 10% X7R  pkg 0402  page 165 : A = P3V3_AUX ; B = GND
PC3272  Q_CAP  1UF 25V 10% X6S  pkg C0402  page 303 : A = HSC_VDD_R_3 ; B = AGND_HSC

(kicad_pcb
	(version 20260206)
	(generator "pcbnew")
	(generator_version "10.0")
	(general
		(thickness 1.6)
		(legacy_teardrops no)
	)
	(paper "A4")
	(title_block
		(title "03242023_DA0F0TMBIJ0_F0T_Motherboard_J_brd_V01_OCP.brd")
		(comment 1 "Grand Teton / footprints 716-717 of 6105")
	)
	(layers
		(0 "F.Cu" signal "TOP")
		(4 "In1.Cu" signal "GND")
		(6 "In2.Cu" signal "IN1")
		(8 "In3.Cu" signal "GND1")
		(10 "In4.Cu" signal "IN2")
		(12 "In5.Cu" signal "GND2")
		(14 "In6.Cu" signal "IN3")
		(16 "In7.Cu" signal "GND3")
		(18 "In8.Cu" signal "VCC")
		(20 "In9.Cu" signal "VCC1")
		(22 "In10.Cu" signal "GND4")
		(24 "In11.Cu" signal "IN4")
		(26 "In12.Cu" signal "GND5")
		(28 "In13.Cu" signal "IN5")
		(30 "In14.Cu" signal "GND6")
		(32 "In15.Cu" signal "IN6")
		(34 "In16.Cu" signal "GND7")
		(2 "B.Cu" signal "BOTTOM")
		(9 "F.Adhes" user "F.Adhesive")
		(11 "B.Adhes" user "B.Adhesive")
		(13 "F.Paste" user "Package Geometry/Pastemask Top")
		(15 "B.Paste" user "Package Geometry/Pastemask Bottom")
		(5 "F.SilkS" user "Ref Des/Silkscreen Top")
		(7 "B.SilkS" user "Ref Des/Silkscreen Bottom")
		(1 "F.Mask" user "Board Geometry/Soldermask Top")
		(3 "B.Mask" user "Board Geometry/Soldermask Bottom")
		(17 "Dwgs.User" user "User.Drawings")
		(19 "Cmts.User" user "User.Comments")
		(21 "Eco1.User" user "User.Eco1")
		(23 "Eco2.User" user "User.Eco2")
		(25 "Edge.Cuts" user "Board Geometry/Outline")
		(27 "Margin" user)
		(31 "F.CrtYd" user "Package Geometry/Place Bound Top")
		(29 "B.CrtYd" user "Package Geometry/Place Bound Bottom")
		(35 "F.Fab" user "Ref Des/Assembly Top")
		(33 "B.Fab" user "Ref Des/Assembly Bottom")
	)
	(footprint ""
		(layer "F.Cu")
		(at 448.31254 -41.747948)
		(property "Reference" "C1874"
			(at 0 0 0)
			(layer "F.SilkS")
			(hide yes)
			(effects
				(font
					(size 1.27 1.27)
				)
			)
		)
		(property "Value" ""
			(at 0 0 0)
			(layer "F.Fab")
			(effects
				(font
					(size 1.27 1.27)
				)
			)
		)
		(duplicate_pad_numbers_are_jumpers no)
		(fp_line
			(start -0.7874 -0.4064)
			(end 0.7874 -0.4064)
			(stroke
				(width 0.1524)
				(type default)
			)
			(layer "F.SilkS")
		)
		(fp_line
			(start -0.7874 0.4064)
			(end -0.7874 -0.4064)
			(stroke
				(width 0.1524)
				(type default)
			)
			(layer "F.SilkS")
		)
		(fp_line
			(start 0.7874 -0.4064)
			(end 0.7874 0.4064)
			(stroke
				(width 0.1524)
				(type default)
			)
			(layer "F.SilkS")
		)
		(fp_line
			(start 0.7874 0.4064)
			(end -0.7874 0.4064)
			(stroke
				(width 0.1524)
				(type default)
			)
			(layer "F.SilkS")
		)
		(fp_line
			(start -0.67945 -0.305054)
			(end -0.12065 -0.305054)
			(stroke
				(width 0.1)
				(type default)
			)
			(layer "F.Fab")
		)
		(fp_line
			(start -0.67945 0.3048)
			(end -0.67945 -0.305054)
			(stroke
				(width 0.1)
				(type default)
			)
			(layer "F.Fab")
		)
		(fp_line
			(start -0.12065 -0.305054)
			(end -0.12065 -0.2794)
			(stroke
				(width 0.1)
				(type default)
			)
			(layer "F.Fab")
		)
		(fp_line
			(start -0.12065 -0.2794)
			(end 0.12065 -0.2794)
			(stroke
				(width 0.1)
				(type default)
			)
			(layer "F.Fab")
		)
		(fp_line
			(start -0.12065 0.2794)
			(end -0.12065 0.3048)
			(stroke
				(width 0.1)
				(type default)
			)
			(layer "F.Fab")
		)
		(fp_line
			(start -0.12065 0.3048)
			(end -0.67945 0.3048)
			(stroke
				(width 0.1)
				(type default)
			)
			(layer "F.Fab")
		)
		(fp_line
			(start 0.120396 0.2794)
			(end -0.12065 0.2794)
			(stroke
				(width 0.1)
				(type default)
			)
			(layer "F.Fab")
		)
		(fp_line
			(start 0.120396 0.3048)
			(end 0.120396 0.2794)
			(stroke
				(width 0.1)
				(type default)
			)
			(layer "F.Fab")
		)
		(fp_line
			(start 0.12065 -0.3048)
			(end 0.67945 -0.3048)
			(stroke
				(width 0.1)
				(type default)
			)
			(layer "F.Fab")
		)
		(fp_line
			(start 0.12065 -0.2794)
			(end 0.12065 -0.3048)
			(stroke
				(width 0.1)
				(type default)
			)
			(layer "F.Fab")
		)
		(fp_line
			(start 0.67945 -0.3048)
			(end 0.67945 0.3048)
			(stroke
				(width 0.1)
				(type default)
			)
			(layer "F.Fab")
		)
		(fp_line
			(start 0.67945 0.3048)
			(end 0.120396 0.3048)
			(stroke
				(width 0.1)
				(type default)
			)
			(layer "F.Fab")
		)
		(pad "1" smd circle
			(at -0.40005 0)
			(size 0 0)
			(layers "F.Cu" "F.Mask" "F.Paste")
			(net "P3V3_AUX")
		)
		(pad "2" smd circle
			(at 0.40005 0)
			(size 0 0)
			(layers "F.Cu" "F.Mask" "F.Paste")
			(net "GND")
		)
	)
	(footprint ""
		(layer "F.Cu")
		(at 217.742008 -402.994622 90)
		(property "Reference" "PC3272"
			(at 0 0 90)
			(layer "F.SilkS")
			(hide yes)
			(effects
				(font
					(size 1.27 1.27)
				)
			)
		)
		(property "Value" ""
			(at 0 0 90)
			(layer "F.Fab")
			(effects
				(font
					(size 1.27 1.27)
				)
			)
		)
		(duplicate_pad_numbers_are_jumpers no)
		(fp_line
			(start 0.7874 -0.4064)
			(end 0.7874 0.4064)
			(stroke
				(width 0.1524)
				(type default)
			)
			(layer "F.SilkS")
		)
		(fp_line
			(start -0.7874 -0.4064)
			(end 0.7874 -0.4064)
			(stroke
				(width 0.1524)
				(type default)
			)
			(layer "F.SilkS")
		)
		(fp_line
			(start 0.7874 0.4064)
			(end -0.7874 0.4064)
			(stroke
				(width 0.1524)
				(type default)
			)
			(layer "F.SilkS")
		)
		(fp_line
			(start -0.7874 0.4064)
			(end -0.7874 -0.4064)
			(stroke
				(width 0.1524)
				(type default)
			)
			(layer "F.SilkS")
		)
		(fp_line
			(start -0.12065 -0.305054)
			(end -0.12065 -0.2794)
			(stroke
				(width 0.1)
				(type default)
			)
			(layer "F.Fab")
		)
		(fp_line
			(start -0.67945 -0.305054)
			(end -0.12065 -0.305054)
			(stroke
				(width 0.1)
				(type default)
			)
			(layer "F.Fab")
		)
		(fp_line
			(start 0.67945 -0.3048)
			(end 0.67945 0.3048)
			(stroke
				(width 0.1)
				(type default)
			)
			(layer "F.Fab")
		)
		(fp_line
			(start 0.12065 -0.3048)
			(end 0.67945 -0.3048)
			(stroke
				(width 0.1)
				(type default)
			)
			(layer "F.Fab")
		)
		(fp_line
			(start 0.12065 -0.2794)
			(end 0.12065 -0.3048)
			(stroke
				(width 0.1)
				(type default)
			)
			(layer "F.Fab")
		)
		(fp_line
			(start -0.12065 -0.2794)
			(end 0.12065 -0.2794)
			(stroke
				(width 0.1)
				(type default)
			)
			(layer "F.Fab")
		)
		(fp_line
			(start 0.120396 0.2794)
			(end -0.12065 0.2794)
			(stroke
				(width 0.1)
				(type default)
			)
			(layer "F.Fab")
		)
		(fp_line
			(start -0.12065 0.2794)
			(end -0.12065 0.3048)
			(stroke
				(width 0.1)
				(type default)
			)
			(layer "F.Fab")
		)
		(fp_line
			(start 0.67945 0.3048)
			(end 0.120396 0.3048)
			(stroke
				(width 0.1)
				(type default)
			)
			(layer "F.Fab")
		)
		(fp_line
			(start 0.120396 0.3048)
			(end 0.120396 0.2794)
			(stroke
				(width 0.1)
				(type default)
			)
			(layer "F.Fab")
		)
		(fp_line
			(start -0.12065 0.3048)
			(end -0.67945 0.3048)
			(stroke
				(width 0.1)
				(type default)
			)
			(layer "F.Fab")
		)
		(fp_line
			(start -0.67945 0.3048)
			(end -0.67945 -0.305054)
			(stroke
				(width 0.1)
				(type default)
			)
			(layer "F.Fab")
		)
		(pad "1" smd circle
			(at -0.40005 0 90)
			(size 0 0)
			(layers "F.Cu" "F.Mask" "F.Paste")
			(net "HSC_VDD_R_3")
		)
		(pad "2" smd circle
			(at 0.40005 0 90)
			(size 0 0)
			(layers "F.Cu" "F.Mask" "F.Paste")
			(net "AGND_HSC")
		)
	)
)
